(kicad_pcb
	(version 20241229)
	(generator "pcbnew")
	(generator_version "9.0")
	(general
		(thickness 1.6)
		(legacy_teardrops no)
	)
	(paper "A4")
	(title_block
		(title "GMSL Deserializer")
		(date "2025-10-09")
		(rev "1.0.4")
		(company "Antmicro Ltd")
		(comment 1 "www.antmicro.com")
		(comment 9 "footprints 56-61 of 235")
	)
	(layers
		(0 "F.Cu" signal)
		(4 "In1.Cu" power)
		(6 "In2.Cu" power)
		(2 "B.Cu" signal)
		(9 "F.Adhes" user "F.Adhesive")
		(11 "B.Adhes" user "B.Adhesive")
		(13 "F.Paste" user)
		(15 "B.Paste" user)
		(5 "F.SilkS" user "F.Silkscreen")
		(7 "B.SilkS" user "B.Silkscreen")
		(1 "F.Mask" user)
		(3 "B.Mask" user)
		(17 "Dwgs.User" user "User.Drawings")
		(19 "Cmts.User" user "User.Comments")
		(21 "Eco1.User" user "User.Eco1")
		(23 "Eco2.User" user "User.Eco2")
		(25 "Edge.Cuts" user)
		(27 "Margin" user)
		(31 "F.CrtYd" user "F.Courtyard")
		(29 "B.CrtYd" user "B.Courtyard")
		(35 "F.Fab" user)
		(33 "B.Fab" user)
	)
	(footprint "antmicro-footprints:L_0806_2016Metric"
		(layer "F.Cu")
		(at 134.519 91.554 180)
		(property "Reference" "L18"
			(at -0.001 1.27 0)
			(layer "F.SilkS")
			(effects
				(font
					(size 0.7 0.7)
					(thickness 0.15)
				)
				(justify right bottom)
			)
		)
		(property "Value" "L_1u_2.6A_0806"
			(at 0 2 0)
			(layer "F.Fab")
			(effects
				(font
					(size 0.7 0.7)
					(thickness 0.15)
				)
				(justify right bottom)
			)
		)
		(property "Datasheet" "https://www.bourns.com/docs/Product-Datasheets/SRP2010.pdf"
			(at 0 0 180)
			(layer "F.Fab")
			(hide yes)
			(effects
				(font
					(size 1.27 1.27)
					(thickness 0.15)
				)
			)
		)
		(property "Description" "Wirewound Inductor, 1 µH, 0.072 ohm, 2.6 A, SRP2010"
			(at 0 0 180)
			(layer "F.Fab")
			(hide yes)
			(effects
				(font
					(size 1.27 1.27)
					(thickness 0.15)
				)
			)
		)
		(property "Author" "Antmicro"
			(at 269.038 183.108 0)
			(layer "F.Fab")
			(hide yes)
			(effects
				(font
					(size 1 1)
					(thickness 0.15)
				)
			)
		)
		(property "IMax" "2.6 A"
			(at 269.038 183.108 0)
			(layer "F.Fab")
			(hide yes)
			(effects
				(font
					(size 1 1)
					(thickness 0.15)
				)
			)
		)
		(property "ISat" "2.9 A"
			(at 269.038 183.108 0)
			(layer "F.Fab")
			(hide yes)
			(effects
				(font
					(size 1 1)
					(thickness 0.15)
				)
			)
		)
		(property "License" "Apache-2.0"
			(at 269.038 183.108 0)
			(layer "F.Fab")
			(hide yes)
			(effects
				(font
					(size 1 1)
					(thickness 0.15)
				)
			)
		)
		(property "MPN" "SRP2010-1R0M"
			(at 269.038 183.108 0)
			(layer "F.Fab")
			(hide yes)
			(effects
				(font
					(size 1 1)
					(thickness 0.15)
				)
			)
		)
		(property "Manufacturer" "Bourns"
			(at 269.038 183.108 0)
			(layer "F.Fab")
			(hide yes)
			(effects
				(font
					(size 1 1)
					(thickness 0.15)
				)
			)
		)
		(property "Size" "2.0x1.6"
			(at 269.038 183.108 0)
			(layer "F.Fab")
			(hide yes)
			(effects
				(font
					(size 1 1)
					(thickness 0.15)
				)
			)
		)
		(property "Val" "1u/2.6A"
			(at 269.038 183.108 0)
			(layer "F.Fab")
			(hide yes)
			(effects
				(font
					(size 1 1)
					(thickness 0.15)
				)
			)
		)
		(sheetname "/Power/")
		(sheetfile "power.kicad_sch")
		(attr smd)
		(fp_line
			(start -0.3 -0.9)
			(end 0.298 -0.9)
			(stroke
				(width 0.15)
				(type solid)
			)
			(layer "F.SilkS")
		)
		(fp_line
			(start -0.301 0.9)
			(end 0.299 0.9)
			(stroke
				(width 0.15)
				(type solid)
			)
			(layer "F.SilkS")
		)
		(fp_rect
			(start -1.75 -1.05)
			(end 1.75 1.05)
			(stroke
				(width 0.05)
				(type solid)
			)
			(fill no)
			(layer "F.CrtYd")
		)
		(fp_rect
			(start -0.951 -0.882)
			(end 0.949 0.875)
			(stroke
				(width 0.15)
				(type solid)
			)
			(fill no)
			(layer "F.Fab")
		)
		(pad "1" smd roundrect
			(at -1.1 -0.001 180)
			(size 1 1.8)
			(layers "F.Cu" "F.Mask" "F.Paste")
			(roundrect_rratio 0.15)
			(net 7 "/Power/SW_1V8")
			(pintype "passive")
		)
		(pad "2" smd roundrect
			(at 1.1 -0.001 180)
			(size 1 1.8)
			(layers "F.Cu" "F.Mask" "F.Paste")
			(roundrect_rratio 0.15)
			(net 10 "/Power/OUT_1V8")
			(pintype "passive")
		)
	)
	(footprint "antmicro-footprints:C_0402_1005Metric"
		(layer "F.Cu")
		(at 131.98 93.078 90)
		(descr "Capacitor SMD 0402")
		(tags "capacitor SMD 0402")
		(property "Reference" "C21"
			(at -0.394 -2.186 90)
			(layer "F.SilkS")
			(effects
				(font
					(size 0.7 0.7)
					(thickness 0.15)
				)
				(justify left bottom)
			)
		)
		(property "Value" "C_22u_0402"
			(at -1.022927 2.155213 90)
			(layer "F.Fab")
			(effects
				(font
					(size 0.7 0.7)
					(thickness 0.15)
				)
				(justify left bottom)
			)
		)
		(property "Datasheet" "https://www.murata.com/products/productdetail?partno=GRM158R60J226ME01%23"
			(at 0 0 90)
			(layer "F.Fab")
			(hide yes)
			(effects
				(font
					(size 1.27 1.27)
					(thickness 0.15)
				)
			)
		)
		(property "Description" "SMD Multilayer Ceramic Capacitor, 22 uF, 4 V, 0402 [1005 Metric], X6S"
			(at 0 0 90)
			(layer "F.Fab")
			(hide yes)
			(effects
				(font
					(size 1.27 1.27)
					(thickness 0.15)
				)
			)
		)
		(property "Author" "Antmicro"
			(at 225.058 -38.902 0)
			(layer "F.Fab")
			(hide yes)
			(effects
				(font
					(size 1 1)
					(thickness 0.15)
				)
			)
		)
		(property "Dielectric" ""
			(at 225.058 -38.902 0)
			(layer "F.Fab")
			(hide yes)
			(effects
				(font
					(size 1 1)
					(thickness 0.15)
				)
			)
		)
		(property "License" "Apache-2.0"
			(at 225.058 -38.902 0)
			(layer "F.Fab")
			(hide yes)
			(effects
				(font
					(size 1 1)
					(thickness 0.15)
				)
			)
		)
		(property "MPN" "GRM158R60J226ME01D"
			(at 225.058 -38.902 0)
			(layer "F.Fab")
			(hide yes)
			(effects
				(font
					(size 1 1)
					(thickness 0.15)
				)
			)
		)
		(property "Manufacturer" "Murata"
			(at 225.058 -38.902 0)
			(layer "F.Fab")
			(hide yes)
			(effects
				(font
					(size 1 1)
					(thickness 0.15)
				)
			)
		)
		(property "Val" "22u"
			(at 225.058 -38.902 0)
			(layer "F.Fab")
			(hide yes)
			(effects
				(font
					(size 1 1)
					(thickness 0.15)
				)
			)
		)
		(property "Voltage" ""
			(at 225.058 -38.902 0)
			(layer "F.Fab")
			(hide yes)
			(effects
				(font
					(size 1 1)
					(thickness 0.15)
				)
			)
		)
		(sheetname "/Power/")
		(sheetfile "power.kicad_sch")
		(attr smd)
		(fp_rect
			(start -0.925 -0.47)
			(end 0.925 0.47)
			(stroke
				(width 0.05)
				(type default)
			)
			(fill no)
			(layer "F.CrtYd")
		)
		(fp_line
			(start 0.504 -0.25)
			(end 0.504 0.248)
			(stroke
				(width 0.15)
				(type solid)
			)
			(layer "F.Fab")
		)
		(fp_line
			(start -0.494 -0.25)
			(end 0.504 -0.25)
			(stroke
				(width 0.15)
				(type solid)
			)
			(layer "F.Fab")
		)
		(fp_line
			(start 0.504 0.248)
			(end -0.494 0.248)
			(stroke
				(width 0.15)
				(type solid)
			)
			(layer "F.Fab")
		)
		(fp_line
			(start -0.494 0.248)
			(end -0.494 -0.25)
			(stroke
				(width 0.15)
				(type solid)
			)
			(layer "F.Fab")
		)
		(pad "1" smd roundrect
			(at -0.48 0 90)
			(size 0.59 0.64)
			(layers "F.Cu" "F.Mask" "F.Paste")
			(roundrect_rratio 0.25)
			(net 1 "GND")
			(pintype "passive")
		)
		(pad "2" smd roundrect
			(at 0.48 0 90)
			(size 0.59 0.64)
			(layers "F.Cu" "F.Mask" "F.Paste")
			(roundrect_rratio 0.25)
			(net 10 "/Power/OUT_1V8")
			(pintype "passive")
		)
	)
	(footprint "antmicro-footprints:R_0402_1005Metric"
		(layer "F.Cu")
		(at 140.208 79.502 -45)
		(descr "Resistor SMD 0402")
		(tags "resistor SMD 0402")
		(property "Reference" "R51"
			(at -1.422699 0.8457 315)
			(unlocked yes)
			(layer "F.SilkS")
			(effects
				(font
					(size 0.7 0.7)
					(thickness 0.15)
				)
				(justify right bottom)
			)
		)
		(property "Value" "R_10k_0402"
			(at -1.011843 1.772046 135)
			(layer "F.Fab")
			(effects
				(font
					(size 0.7 0.7)
					(thickness 0.15)
				)
				(justify right bottom)
			)
		)
		(property "Datasheet" "https://www.bourns.com/docs/product-datasheets/cr.pdf"
			(at 0 0 315)
			(layer "F.Fab")
			(hide yes)
			(effects
				(font
					(size 1.27 1.27)
					(thickness 0.15)
				)
			)
		)
		(property "Description" "SMD Chip Resistor, 10 kohm, ± 1%, 62.5 mW, 0402 [1005 Metric], Thick Film, General Purpose"
			(at 0 0 315)
			(layer "F.Fab")
			(hide yes)
			(effects
				(font
					(size 1.27 1.27)
					(thickness 0.15)
				)
			)
		)
		(property "Author" "Antmicro"
			(at -15.150431 122.427625 0)
			(layer "F.Fab")
			(hide yes)
			(effects
				(font
					(size 1 1)
					(thickness 0.15)
				)
			)
		)
		(property "License" "Apache-2.0"
			(at -15.150431 122.427625 0)
			(layer "F.Fab")
			(hide yes)
			(effects
				(font
					(size 1 1)
					(thickness 0.15)
				)
			)
		)
		(property "MPN" "CR0402-FX-1002GLF"
			(at -15.150431 122.427625 0)
			(layer "F.Fab")
			(hide yes)
			(effects
				(font
					(size 1 1)
					(thickness 0.15)
				)
			)
		)
		(property "Manufacturer" "Bourns"
			(at -15.150431 122.427625 0)
			(layer "F.Fab")
			(hide yes)
			(effects
				(font
					(size 1 1)
					(thickness 0.15)
				)
			)
		)
		(property "Tolerance" "1%"
			(at -15.150431 122.427625 0)
			(layer "F.Fab")
			(hide yes)
			(effects
				(font
					(size 1 1)
					(thickness 0.15)
				)
			)
		)
		(property "Val" "10k"
			(at -15.150431 122.427625 0)
			(layer "F.Fab")
			(hide yes)
			(effects
				(font
					(size 1 1)
					(thickness 0.15)
				)
			)
		)
		(sheetname "/Deserializer/")
		(sheetfile "deserializer.kicad_sch")
		(attr smd)
		(fp_poly
			(pts
				(xy -0.925 -0.47) (xy 0.925 -0.47) (xy 0.925 0.47) (xy -0.925 0.47)
			)
			(stroke
				(width 0.05)
				(type default)
			)
			(fill no)
			(layer "F.CrtYd")
		)
		(fp_poly
			(pts
				(xy -0.5 -0.25) (xy 0.5 -0.25) (xy 0.5 0.25) (xy -0.5 0.25)
			)
			(stroke
				(width 0.15)
				(type solid)
			)
			(fill no)
			(layer "F.Fab")
		)
		(pad "1" smd roundrect
			(at -0.48 0 315)
			(size 0.59 0.64)
			(layers "F.Cu" "F.Mask" "F.Paste")
			(roundrect_rratio 0.25)
			(net 1 "GND")
			(pintype "passive")
		)
		(pad "2" smd roundrect
			(at 0.48 0 315)
			(size 0.59 0.64)
			(layers "F.Cu" "F.Mask" "F.Paste")
			(roundrect_rratio 0.25)
			(net 77 "/Deserializer/CFG1")
			(pintype "passive")
		)
	)
	(footprint "antmicro-footprints:R_0402_1005Metric"
		(layer "F.Cu")
		(at 185.674 54.864)
		(descr "Resistor SMD 0402")
		(tags "resistor SMD 0402")
		(property "Reference" "R42"
			(at -2.413 2.159 0)
			(layer "F.SilkS")
			(effects
				(font
					(size 0.7 0.7)
					(thickness 0.15)
				)
				(justify left bottom)
			)
		)
		(property "Value" "R_6k8_0402"
			(at -1.011843 1.772047 0)
			(layer "F.Fab")
			(effects
				(font
					(size 0.7 0.7)
					(thickness 0.15)
				)
				(justify left bottom)
			)
		)
		(property "Datasheet" "https://www.bourns.com/docs/product-datasheets/cr.pdf"
			(at 0 0 0)
			(layer "F.Fab")
			(hide yes)
			(effects
				(font
					(size 1.27 1.27)
					(thickness 0.15)
				)
			)
		)
		(property "Description" "SMD Chip Resistor, 6.8 kohm, ± 1%, 63 mW, 0402 [1005 Metric], Thick Film, General Purpose"
			(at 0 0 0)
			(layer "F.Fab")
			(hide yes)
			(effects
				(font
					(size 1.27 1.27)
					(thickness 0.15)
				)
			)
		)
		(property "Author" "Antmicro"
			(at 0 0 0)
			(layer "F.Fab")
			(hide yes)
			(effects
				(font
					(size 1 1)
					(thickness 0.15)
				)
			)
		)
		(property "License" "Apache-2.0"
			(at 0 0 0)
			(layer "F.Fab")
			(hide yes)
			(effects
				(font
					(size 1 1)
					(thickness 0.15)
				)
			)
		)
		(property "MPN" "CR0402-FX-6801GLF"
			(at 0 0 0)
			(layer "F.Fab")
			(hide yes)
			(effects
				(font
					(size 1 1)
					(thickness 0.15)
				)
			)
		)
		(property "Manufacturer" "Bourns"
			(at 0 0 0)
			(layer "F.Fab")
			(hide yes)
			(effects
				(font
					(size 1 1)
					(thickness 0.15)
				)
			)
		)
		(property "Tolerance" "1%"
			(at 0 0 0)
			(layer "F.Fab")
			(hide yes)
			(effects
				(font
					(size 1 1)
					(thickness 0.15)
				)
			)
		)
		(property "Val" "6k8"
			(at 0 0 0)
			(layer "F.Fab")
			(hide yes)
			(effects
				(font
					(size 1 1)
					(thickness 0.15)
				)
			)
		)
		(sheetname "/Power/")
		(sheetfile "power.kicad_sch")
		(attr smd)
		(fp_rect
			(start -0.925 -0.47)
			(end 0.925 0.47)
			(stroke
				(width 0.05)
				(type default)
			)
			(fill no)
			(layer "F.CrtYd")
		)
		(fp_rect
			(start -0.5 -0.25)
			(end 0.5 0.25)
			(stroke
				(width 0.15)
				(type solid)
			)
			(fill no)
			(layer "F.Fab")
		)
		(pad "1" smd roundrect
			(at -0.48 0)
			(size 0.59 0.64)
			(layers "F.Cu" "F.Mask" "F.Paste")
			(roundrect_rratio 0.25)
			(net 1 "GND")
			(pintype "passive")
		)
		(pad "2" smd roundrect
			(at 0.48 0)
			(size 0.59 0.64)
			(layers "F.Cu" "F.Mask" "F.Paste")
			(roundrect_rratio 0.25)
			(net 74 "/Power/FFC_5V_ISET")
			(pintype "passive")
		)
	)
	(footprint "antmicro-footprints:C_0402_1005Metric"
		(layer "F.Cu")
		(at 140.589 75.819 135)
		(descr "Capacitor SMD 0402")
		(tags "capacitor SMD 0402")
		(property "Reference" "C32"
			(at 6.272037 -0.486489 315)
			(unlocked yes)
			(layer "F.SilkS")
			(effects
				(font
					(size 0.7 0.7)
					(thickness 0.15)
				)
				(justify left bottom)
			)
		)
		(property "Value" "C_100n_0402"
			(at -21.596927 15.617213 135)
			(layer "F.Fab")
			(effects
				(font
					(size 0.7 0.7)
					(thickness 0.15)
				)
				(justify left bottom)
			)
		)
		(property "Datasheet" "https://www.murata.com/products/productdetail?partno=GRM155R61H104KE14%23"
			(at 0 0 135)
			(layer "F.Fab")
			(hide yes)
			(effects
				(font
					(size 1.27 1.27)
					(thickness 0.15)
				)
			)
		)
		(property "Description" "SMD Multilayer Ceramic Capacitor, 0.1 µF, 50 V, 0402 [1005 Metric], ± 10%, X5R, GRM Series"
			(at 0 0 135)
			(layer "F.Fab")
			(hide yes)
			(effects
				(font
					(size 1.27 1.27)
					(thickness 0.15)
				)
			)
		)
		(property "Author" "Antmicro"
			(at 293.612564 30.019694 0)
			(layer "F.Fab")
			(hide yes)
			(effects
				(font
					(size 1 1)
					(thickness 0.15)
				)
			)
		)
		(property "Dielectric" "X5R"
			(at 293.612564 30.019694 0)
			(layer "F.Fab")
			(hide yes)
			(effects
				(font
					(size 1 1)
					(thickness 0.15)
				)
			)
		)
		(property "License" "Apache-2.0"
			(at 293.612564 30.019694 0)
			(layer "F.Fab")
			(hide yes)
			(effects
				(font
					(size 1 1)
					(thickness 0.15)
				)
			)
		)
		(property "MPN" "GRM155R61H104KE14D"
			(at 293.612564 30.019694 0)
			(layer "F.Fab")
			(hide yes)
			(effects
				(font
					(size 1 1)
					(thickness 0.15)
				)
			)
		)
		(property "Manufacturer" "Murata"
			(at 293.612564 30.019694 0)
			(layer "F.Fab")
			(hide yes)
			(effects
				(font
					(size 1 1)
					(thickness 0.15)
				)
			)
		)
		(property "Val" "100n"
			(at 293.612564 30.019694 0)
			(layer "F.Fab")
			(hide yes)
			(effects
				(font
					(size 1 1)
					(thickness 0.15)
				)
			)
		)
		(property "Voltage" "50V"
			(at 293.612564 30.019694 0)
			(layer "F.Fab")
			(hide yes)
			(effects
				(font
					(size 1 1)
					(thickness 0.15)
				)
			)
		)
		(sheetname "/Deserializer/")
		(sheetfile "deserializer.kicad_sch")
		(attr smd)
		(fp_poly
			(pts
				(xy -0.925 -0.47) (xy 0.925 -0.47) (xy 0.925 0.47) (xy -0.925 0.47)
			)
			(stroke
				(width 0.05)
				(type default)
			)
			(fill no)
			(layer "F.CrtYd")
		)
		(fp_line
			(start 0.504 -0.25)
			(end 0.504 0.248)
			(stroke
				(width 0.15)
				(type solid)
			)
			(layer "F.Fab")
		)
		(fp_line
			(start 0.504 0.248)
			(end -0.494 0.248)
			(stroke
				(width 0.15)
				(type solid)
			)
			(layer "F.Fab")
		)
		(fp_line
			(start -0.494 -0.25)
			(end 0.504 -0.25)
			(stroke
				(width 0.15)
				(type solid)
			)
			(layer "F.Fab")
		)
		(fp_line
			(start -0.494 0.248)
			(end -0.494 -0.25)
			(stroke
				(width 0.15)
				(type solid)
			)
			(layer "F.Fab")
		)
		(pad "1" smd roundrect
			(at -0.48 0 135)
			(size 0.59 0.64)
			(layers "F.Cu" "F.Mask" "F.Paste")
			(roundrect_rratio 0.25)
			(net 18 "/Deserializer/SIOA_N")
			(pintype "passive")
		)
		(pad "2" smd roundrect
			(at 0.48 0 135)
			(size 0.59 0.64)
			(layers "F.Cu" "F.Mask" "F.Paste")
			(roundrect_rratio 0.25)
			(net 19 "Net-(C32-Pad2)")
			(pintype "passive")
		)
	)
	(footprint "antmicro-footprints:C_0402_1005Metric"
		(layer "F.Cu")
		(at 137.567 92.824 90)
		(descr "Capacitor SMD 0402")
		(tags "capacitor SMD 0402")
		(property "Reference" "C19"
			(at 1.13 0.355 90)
			(layer "F.SilkS")
			(effects
				(font
					(size 0.7 0.7)
					(thickness 0.15)
				)
				(justify left bottom)
			)
		)
		(property "Value" "C_100n_0402"
			(at -1.022927 2.155213 90)
			(layer "F.Fab")
			(effects
				(font
					(size 0.7 0.7)
					(thickness 0.15)
				)
				(justify left bottom)
			)
		)
		(property "Datasheet" "https://www.murata.com/products/productdetail?partno=GRM155R61H104KE14%23"
			(at 0 0 90)
			(layer "F.Fab")
			(hide yes)
			(effects
				(font
					(size 1.27 1.27)
					(thickness 0.15)
				)
			)
		)
		(property "Description" "SMD Multilayer Ceramic Capacitor, 0.1 µF, 50 V, 0402 [1005 Metric], ± 10%, X5R, GRM Series"
			(at 0 0 90)
			(layer "F.Fab")
			(hide yes)
			(effects
				(font
					(size 1.27 1.27)
					(thickness 0.15)
				)
			)
		)
		(property "Author" "Antmicro"
			(at 230.391 -44.743 0)
			(layer "F.Fab")
			(hide yes)
			(effects
				(font
					(size 1 1)
					(thickness 0.15)
				)
			)
		)
		(property "Dielectric" "X5R"
			(at 230.391 -44.743 0)
			(layer "F.Fab")
			(hide yes)
			(effects
				(font
					(size 1 1)
					(thickness 0.15)
				)
			)
		)
		(property "License" "Apache-2.0"
			(at 230.391 -44.743 0)
			(layer "F.Fab")
			(hide yes)
			(effects
				(font
					(size 1 1)
					(thickness 0.15)
				)
			)
		)
		(property "MPN" "GRM155R61H104KE14D"
			(at 230.391 -44.743 0)
			(layer "F.Fab")
			(hide yes)
			(effects
				(font
					(size 1 1)
					(thickness 0.15)
				)
			)
		)
		(property "Manufacturer" "Murata"
			(at 230.391 -44.743 0)
			(layer "F.Fab")
			(hide yes)
			(effects
				(font
					(size 1 1)
					(thickness 0.15)
				)
			)
		)
		(property "Val" "100n"
			(at 230.391 -44.743 0)
			(layer "F.Fab")
			(hide yes)
			(effects
				(font
					(size 1 1)
					(thickness 0.15)
				)
			)
		)
		(property "Voltage" "50V"
			(at 230.391 -44.743 0)
			(layer "F.Fab")
			(hide yes)
			(effects
				(font
					(size 1 1)
					(thickness 0.15)
				)
			)
		)
		(sheetname "/Power/")
		(sheetfile "power.kicad_sch")
		(attr smd)
		(fp_rect
			(start -0.925 -0.47)
			(end 0.925 0.47)
			(stroke
				(width 0.05)
				(type default)
			)
			(fill no)
			(layer "F.CrtYd")
		)
		(fp_line
			(start 0.504 -0.25)
			(end 0.504 0.248)
			(stroke
				(width 0.15)
				(type solid)
			)
			(layer "F.Fab")
		)
		(fp_line
			(start -0.494 -0.25)
			(end 0.504 -0.25)
			(stroke
				(width 0.15)
				(type solid)
			)
			(layer "F.Fab")
		)
		(fp_line
			(start 0.504 0.248)
			(end -0.494 0.248)
			(stroke
				(width 0.15)
				(type solid)
			)
			(layer "F.Fab")
		)
		(fp_line
			(start -0.494 0.248)
			(end -0.494 -0.25)
			(stroke
				(width 0.15)
				(type solid)
			)
			(layer "F.Fab")
		)
		(pad "1" smd roundrect
			(at -0.48 0 90)
			(size 0.59 0.64)
			(layers "F.Cu" "F.Mask" "F.Paste")
			(roundrect_rratio 0.25)
			(net 6 "Net-(U4-BST)")
			(pintype "passive")
		)
		(pad "2" smd roundrect
			(at 0.48 0 90)
			(size 0.59 0.64)
			(layers "F.Cu" "F.Mask" "F.Paste")
			(roundrect_rratio 0.25)
			(net 7 "/Power/SW_1V8")
			(pintype "passive")
		)
	)
)
